# SCM (Grand Teton) — schematic netlist excerpt (pin names and nets, part order shuffled) for the footprints in the layout excerpt that follows; sources: Cadence DE-HDL packaged netlist, KiCad conversion of 12092022_DA0F0TMDCD0_F0T_Management_Board_D_brd_V3_OCP.brd

R38  Q_RES  4.7K 1% CHIP  pkg 0402LF  page 13 : A = P3V3_AUX ; B = FM_BMC_SUSACK_N

X1  TP_TDR_4P_FTS  TP_TDR_4P_DIP EMPTY  pkg TH  page 60
  S1  = TDR_DIFF_85_TOP_DP
  P1  = GND_P1
  P2  = GND_P1
  S2  = TDR_DIFF_85_TOP_DN

(kicad_pcb
	(version 20260206)
	(generator "pcbnew")
	(generator_version "10.0")
	(general
		(thickness 1.6)
		(legacy_teardrops no)
	)
	(paper "A4")
	(title_block
		(title "12092022_DA0F0TMDCD0_F0T_Management_Board_D_brd_V3_OCP.brd")
		(comment 1 "Grand Teton / footprints 1090-1091 of 1440")
	)
	(layers
		(0 "F.Cu" signal "TOP")
		(4 "In1.Cu" signal "GND")
		(6 "In2.Cu" signal "IN1")
		(8 "In3.Cu" signal "GND1")
		(10 "In4.Cu" signal "IN2")
		(12 "In5.Cu" signal "VCC")
		(14 "In6.Cu" signal "VCC1")
		(16 "In7.Cu" signal "IN3")
		(18 "In8.Cu" signal "GND2")
		(20 "In9.Cu" signal "IN4")
		(22 "In10.Cu" signal "GND3")
		(2 "B.Cu" signal "BOTTOM")
		(9 "F.Adhes" user "F.Adhesive")
		(11 "B.Adhes" user "B.Adhesive")
		(13 "F.Paste" user "Package Geometry/Pastemask Top")
		(15 "B.Paste" user "Package Geometry/Pastemask Bottom")
		(5 "F.SilkS" user "Ref Des/Silkscreen Top")
		(7 "B.SilkS" user "Ref Des/Silkscreen Bottom")
		(1 "F.Mask" user "Board Geometry/Soldermask Top")
		(3 "B.Mask" user "Board Geometry/Soldermask Bottom")
		(17 "Dwgs.User" user "User.Drawings")
		(19 "Cmts.User" user "User.Comments")
		(21 "Eco1.User" user "User.Eco1")
		(23 "Eco2.User" user "User.Eco2")
		(25 "Edge.Cuts" user "Board Geometry/Outline")
		(27 "Margin" user)
		(31 "F.CrtYd" user "Package Geometry/Place Bound Top")
		(29 "B.CrtYd" user "Package Geometry/Place Bound Bottom")
		(35 "F.Fab" user "Ref Des/Assembly Top")
		(33 "B.Fab" user "Ref Des/Assembly Bottom")
	)
	(footprint ""
		(layer "B.Cu")
		(at 52.959 -66.1416 -90)
		(property "Reference" "R38"
			(at 0 0 90)
			(layer "B.SilkS")
			(hide yes)
			(effects
				(font
					(size 1.27 1.27)
				)
				(justify mirror)
			)
		)
		(property "Value" ""
			(at 0 0 90)
			(layer "B.Fab")
			(effects
				(font
					(size 1.27 1.27)
				)
				(justify mirror)
			)
		)
		(duplicate_pad_numbers_are_jumpers no)
		(fp_line
			(start -0.7874 0.4064)
			(end 0.7874 0.4064)
			(stroke
				(width 0.1524)
				(type default)
			)
			(layer "B.SilkS")
		)
		(fp_line
			(start 0.7874 0.4064)
			(end 0.7874 -0.4064)
			(stroke
				(width 0.1524)
				(type default)
			)
			(layer "B.SilkS")
		)
		(fp_line
			(start -0.7874 -0.4064)
			(end -0.7874 0.4064)
			(stroke
				(width 0.1524)
				(type default)
			)
			(layer "B.SilkS")
		)
		(fp_line
			(start 0.7874 -0.4064)
			(end -0.7874 -0.4064)
			(stroke
				(width 0.1524)
				(type default)
			)
			(layer "B.SilkS")
		)
		(fp_line
			(start -0.67945 0.3048)
			(end -0.120396 0.3048)
			(stroke
				(width 0.1)
				(type default)
			)
			(layer "B.Fab")
		)
		(fp_line
			(start -0.120396 0.3048)
			(end -0.120396 0.2794)
			(stroke
				(width 0.1)
				(type default)
			)
			(layer "B.Fab")
		)
		(fp_line
			(start 0.12065 0.3048)
			(end 0.67945 0.3048)
			(stroke
				(width 0.1)
				(type default)
			)
			(layer "B.Fab")
		)
		(fp_line
			(start 0.67945 0.3048)
			(end 0.67945 -0.305054)
			(stroke
				(width 0.1)
				(type default)
			)
			(layer "B.Fab")
		)
		(fp_line
			(start -0.120396 0.2794)
			(end 0.12065 0.2794)
			(stroke
				(width 0.1)
				(type default)
			)
			(layer "B.Fab")
		)
		(fp_line
			(start 0.12065 0.2794)
			(end 0.12065 0.3048)
			(stroke
				(width 0.1)
				(type default)
			)
			(layer "B.Fab")
		)
		(fp_line
			(start -0.12065 -0.2794)
			(end -0.12065 -0.3048)
			(stroke
				(width 0.1)
				(type default)
			)
			(layer "B.Fab")
		)
		(fp_line
			(start 0.12065 -0.2794)
			(end -0.12065 -0.2794)
			(stroke
				(width 0.1)
				(type default)
			)
			(layer "B.Fab")
		)
		(fp_line
			(start -0.67945 -0.3048)
			(end -0.67945 0.3048)
			(stroke
				(width 0.1)
				(type default)
			)
			(layer "B.Fab")
		)
		(fp_line
			(start -0.12065 -0.3048)
			(end -0.67945 -0.3048)
			(stroke
				(width 0.1)
				(type default)
			)
			(layer "B.Fab")
		)
		(fp_line
			(start 0.12065 -0.305054)
			(end 0.12065 -0.2794)
			(stroke
				(width 0.1)
				(type default)
			)
			(layer "B.Fab")
		)
		(fp_line
			(start 0.67945 -0.305054)
			(end 0.12065 -0.305054)
			(stroke
				(width 0.1)
				(type default)
			)
			(layer "B.Fab")
		)
		(pad "1" smd circle
			(at 0.40005 0 90)
			(size 0 0)
			(layers "B.Cu" "B.Mask" "B.Paste")
			(net "P3V3_AUX")
		)
		(pad "2" smd circle
			(at -0.40005 0 90)
			(size 0 0)
			(layers "B.Cu" "B.Mask" "B.Paste")
			(net "FM_BMC_SUSACK_N")
		)
	)
	(footprint ""
		(layer "B.Cu")
		(at 112.014 -85.344 90)
		(property "Reference" "X1"
			(at 1.73863 2.4638 0)
			(unlocked yes)
			(layer "B.SilkS")
			(effects
				(font
					(size 0.7874 0.5842)
					(thickness 0.1524)
				)
				(justify left mirror)
			)
		)
		(property "Value" ""
			(at 0 0 90)
			(layer "B.Fab")
			(effects
				(font
					(size 1.27 1.27)
				)
				(justify mirror)
			)
		)
		(property "Device Type" "TP_TDR_4P_FTS_TH-TP_TDR_4P_DIPA"
			(at -1.30175 1.27 0)
			(unlocked yes)
			(layer "B.Fab")
			(hide yes)
			(effects
				(font
					(size 0.635 0.4064)
					(thickness 0.1524)
				)
				(justify mirror)
			)
		)
		(property "User Part Number" "N_A"
			(at -1.30175 1.27 0)
			(unlocked yes)
			(layer "Cmts.User")
			(hide yes)
			(effects
				(font
					(size 0.635 0.4064)
					(thickness 0.1524)
				)
				(justify mirror)
			)
		)
		(duplicate_pad_numbers_are_jumpers no)
		(fp_line
			(start 0 -1.27)
			(end 0 -0.635)
			(stroke
				(width 0.1524)
				(type default)
			)
			(layer "B.SilkS")
		)
		(fp_line
			(start -2.54 -1.27)
			(end 0 -1.27)
			(stroke
				(width 0.1524)
				(type default)
			)
			(layer "B.SilkS")
		)
		(fp_line
			(start -2.54 -1.1303)
			(end -2.54 -1.27)
			(stroke
				(width 0.1524)
				(type default)
			)
			(layer "B.SilkS")
		)
		(fp_line
			(start 0 0.635)
			(end 0 1.905)
			(stroke
				(width 0.1524)
				(type default)
			)
			(layer "B.SilkS")
		)
		(fp_line
			(start -2.54 1.4097)
			(end -2.54 1.1303)
			(stroke
				(width 0.1524)
				(type default)
			)
			(layer "B.SilkS")
		)
		(fp_line
			(start 0 3.175)
			(end 0 3.81)
			(stroke
				(width 0.1524)
				(type default)
			)
			(layer "B.SilkS")
		)
		(fp_line
			(start 0 3.81)
			(end -2.54 3.81)
			(stroke
				(width 0.1524)
				(type default)
			)
			(layer "B.SilkS")
		)
		(fp_line
			(start -2.54 3.81)
			(end -2.54 3.6703)
			(stroke
				(width 0.1524)
				(type default)
			)
			(layer "B.SilkS")
		)
		(fp_poly
			(pts
				(xy 0.761746 0) (xy 2.285746 -0.762) (xy 2.285746 0.762)
			)
			(stroke
				(width 0)
				(type default)
			)
			(fill yes)
			(layer "B.SilkS")
		)
		(fp_line
			(start 0 -1.27)
			(end 0 3.81)
			(stroke
				(width 0.1)
				(type default)
			)
			(layer "B.Fab")
		)
		(fp_line
			(start -2.54 -1.27)
			(end 0 -1.27)
			(stroke
				(width 0.1)
				(type default)
			)
			(layer "B.Fab")
		)
		(fp_line
			(start 0 3.81)
			(end -2.54 3.81)
			(stroke
				(width 0.1)
				(type default)
			)
			(layer "B.Fab")
		)
		(fp_line
			(start -2.54 3.81)
			(end -2.54 -1.27)
			(stroke
				(width 0.1)
				(type default)
			)
			(layer "B.Fab")
		)
		(fp_poly
			(pts
				(xy 0.761746 0) (xy 2.285746 -0.762) (xy 2.285746 0.762)
			)
			(stroke
				(width 0)
				(type default)
			)
			(fill yes)
			(layer "B.Fab")
		)
		(pad "1" thru_hole circle
			(at 0 0 270)
			(size 1.0033 1.0033)
			(drill 0.249936)
			(layers "*.Cu" "*.Mask")
			(remove_unused_layers no)
			(net "TDR_DIFF_85_TOP_DP")
			(clearance 0.10795)
			(padstack
				(mode front_inner_back)
				(layer "Inner"
					(shape circle)
					(size 0.8001 0.8001)
					(clearance 0.1524)
				)
				(layer "B.Cu"
					(shape circle)
					(size 1.0033 1.0033)
					(thermal_gap 0.10795)
					(clearance 0.10795)
				)
			)
		)
		(pad "2" thru_hole circle
			(at -2.54 0 270)
			(size 1.9939 1.9939)
			(drill 0.249936)
			(layers "*.Cu" "*.Mask")
			(remove_unused_layers no)
			(net "GND_P1")
			(clearance 0.10795)
			(padstack
				(mode front_inner_back)
				(layer "Inner"
					(shape circle)
					(size 0.8001 0.8001)
					(clearance 0.1524)
				)
				(layer "B.Cu"
					(shape circle)
					(size 1.9939 1.9939)
					(thermal_gap 0.10795)
					(clearance 0.10795)
				)
			)
		)
		(pad "3" thru_hole circle
			(at -2.54 2.54 270)
			(size 1.9939 1.9939)
			(drill 0.249936)
			(layers "*.Cu" "*.Mask")
			(remove_unused_layers no)
			(net "GND_P1")
			(clearance 0.10795)
			(padstack
				(mode front_inner_back)
				(layer "Inner"
					(shape circle)
					(size 0.8001 0.8001)
					(clearance 0.1524)
				)
				(layer "B.Cu"
					(shape circle)
					(size 1.9939 1.9939)
					(thermal_gap 0.10795)
					(clearance 0.10795)
				)
			)
		)
		(pad "4" thru_hole circle
			(at 0 2.54 270)
			(size 1.0033 1.0033)
			(drill 0.249936)
			(layers "*.Cu" "*.Mask")
			(remove_unused_layers no)
			(net "TDR_DIFF_85_TOP_DN")
			(clearance 0.10795)
			(padstack
				(mode front_inner_back)
				(layer "Inner"
					(shape circle)
					(size 0.8001 0.8001)
					(clearance 0.1524)
				)
				(layer "B.Cu"
					(shape circle)
					(size 1.0033 1.0033)
					(thermal_gap 0.10795)
					(clearance 0.10795)
				)
			)
		)
	)
)
